(kicad_pcb
	(version 20241229)
	(generator "pcbnew")
	(generator_version "9.0")
	(general
		(thickness 1.258)
		(legacy_teardrops no)
	)
	(paper "A4")
	(title_block
		(date "2024-05-27")
		(rev "1.1.2")
		(comment 9 "footprints 8-14 of 64")
	)
	(layers
		(0 "F.Cu" signal)
		(4 "In1.Cu" power)
		(6 "In2.Cu" power)
		(8 "In3.Cu" signal)
		(10 "In4.Cu" signal)
		(2 "B.Cu" signal)
		(9 "F.Adhes" user "F.Adhesive")
		(11 "B.Adhes" user "B.Adhesive")
		(13 "F.Paste" user)
		(15 "B.Paste" user)
		(5 "F.SilkS" user "F.Silkscreen")
		(7 "B.SilkS" user "B.Silkscreen")
		(1 "F.Mask" user)
		(3 "B.Mask" user)
		(17 "Dwgs.User" user "User.Drawings")
		(19 "Cmts.User" user "User.Comments")
		(21 "Eco1.User" user "User.Eco1")
		(23 "Eco2.User" user "User.Eco2")
		(25 "Edge.Cuts" user)
		(27 "Margin" user)
		(31 "F.CrtYd" user "F.Courtyard")
		(29 "B.CrtYd" user "B.Courtyard")
		(35 "F.Fab" user)
		(33 "B.Fab" user)
	)
	(footprint "antmicro-footprints:LED_0603_1608Metric_G"
		(layer "F.Cu")
		(at 125.625 72.9 90)
		(descr "LED SMD 0603 Green")
		(tags "LED SMD 0603 Green")
		(property "Reference" "D1"
			(at 1.56 -0.715 180)
			(layer "F.SilkS")
			(effects
				(font
					(size 0.7 0.7)
					(thickness 0.15)
				)
				(justify left bottom)
			)
		)
		(property "Value" "LED_G_0603_KP-1608CGCK"
			(at 0 1.6 90)
			(layer "F.Fab")
			(hide yes)
			(effects
				(font
					(size 0.7 0.7)
					(thickness 0.15)
				)
				(justify left bottom)
			)
		)
		(property "Author" "Antmicro"
			(at 198.525 -52.725 0)
			(layer "F.Fab")
			(hide yes)
			(effects
				(font
					(size 1 1)
					(thickness 0.15)
				)
			)
		)
		(property "License" "Apache-2.0"
			(at 198.525 -52.725 0)
			(layer "F.Fab")
			(hide yes)
			(effects
				(font
					(size 1 1)
					(thickness 0.15)
				)
			)
		)
		(property "MPN" "KP-1608CGCK"
			(at 198.525 -52.725 0)
			(layer "F.Fab")
			(hide yes)
			(effects
				(font
					(size 1 1)
					(thickness 0.15)
				)
			)
		)
		(property "Manufacturer" "Kingbright"
			(at 198.525 -52.725 0)
			(layer "F.Fab")
			(hide yes)
			(effects
				(font
					(size 1 1)
					(thickness 0.15)
				)
			)
		)
		(sheetname "EEPROM")
		(sheetfile "EEPROM.kicad_sch")
		(attr smd)
		(fp_line
			(start 0.22 -0.35)
			(end -0.22 -0.35)
			(stroke
				(width 0.15)
				(type solid)
			)
			(layer "F.SilkS")
		)
		(fp_line
			(start -1.18 -0.319)
			(end -1.18 0.321)
			(stroke
				(width 0.15)
				(type solid)
			)
			(layer "F.SilkS")
		)
		(fp_line
			(start 0.105328 0.001008)
			(end 0.24 0.001)
			(stroke
				(width 0.1)
				(type solid)
			)
			(layer "F.SilkS")
		)
		(fp_line
			(start -0.094672 0.001008)
			(end 0.105328 -0.198992)
			(stroke
				(width 0.1)
				(type solid)
			)
			(layer "F.SilkS")
		)
		(fp_line
			(start -0.094672 0.001008)
			(end -0.24 0.001008)
			(stroke
				(width 0.1)
				(type solid)
			)
			(layer "F.SilkS")
		)
		(fp_line
			(start 0.105328 0.201008)
			(end 0.105328 -0.198992)
			(stroke
				(width 0.1)
				(type solid)
			)
			(layer "F.SilkS")
		)
		(fp_line
			(start 0.105328 0.201008)
			(end -0.094672 0.001008)
			(stroke
				(width 0.1)
				(type solid)
			)
			(layer "F.SilkS")
		)
		(fp_line
			(start -0.094672 0.201008)
			(end -0.094672 -0.198992)
			(stroke
				(width 0.1)
				(type solid)
			)
			(layer "F.SilkS")
		)
		(fp_line
			(start 0.22 0.35)
			(end -0.22 0.35)
			(stroke
				(width 0.15)
				(type solid)
			)
			(layer "F.SilkS")
		)
		(fp_rect
			(start 1.25 0.65)
			(end -1.25 -0.65)
			(stroke
				(width 0.05)
				(type solid)
			)
			(fill no)
			(layer "F.CrtYd")
		)
		(fp_line
			(start 0.201 -0.202)
			(end -0.101 0)
			(stroke
				(width 0.15)
				(type solid)
			)
			(layer "F.Fab")
		)
		(fp_line
			(start -0.199 -0.202)
			(end -0.199 0.1)
			(stroke
				(width 0.15)
				(type solid)
			)
			(layer "F.Fab")
		)
		(fp_line
			(start 0.599 0)
			(end 0.201 0)
			(stroke
				(width 0.15)
				(type solid)
			)
			(layer "F.Fab")
		)
		(fp_line
			(start 0.201 0)
			(end 0.201 -0.202)
			(stroke
				(width 0.15)
				(type solid)
			)
			(layer "F.Fab")
		)
		(fp_line
			(start -0.101 0)
			(end 0.201 0.2)
			(stroke
				(width 0.15)
				(type solid)
			)
			(layer "F.Fab")
		)
		(fp_line
			(start -0.199 0)
			(end -0.597 0)
			(stroke
				(width 0.15)
				(type solid)
			)
			(layer "F.Fab")
		)
		(fp_line
			(start 0.201 0.2)
			(end 0.201 0)
			(stroke
				(width 0.15)
				(type solid)
			)
			(layer "F.Fab")
		)
		(fp_line
			(start -0.199 0.2)
			(end -0.199 0.1)
			(stroke
				(width 0.15)
				(type solid)
			)
			(layer "F.Fab")
		)
		(fp_rect
			(start 0.848 0.4)
			(end -0.85 -0.402)
			(stroke
				(width 0.15)
				(type solid)
			)
			(fill no)
			(layer "F.Fab")
		)
		(pad "1" smd roundrect
			(at -0.7 0 270)
			(size 0.8 1)
			(layers "F.Cu" "F.Mask" "F.Paste")
			(roundrect_rratio 0.2)
			(net 4 "Net-(D1-Pad1)")
			(pinfunction "1")
			(pintype "passive")
		)
		(pad "2" smd roundrect
			(at 0.7 0 270)
			(size 0.8 1)
			(layers "F.Cu" "F.Mask" "F.Paste")
			(roundrect_rratio 0.2)
			(net 1 "GND")
			(pinfunction "2")
			(pintype "passive")
		)
	)
	(footprint "antmicro-footprints:SOT-23-5"
		(layer "F.Cu")
		(at 129.375 91.15)
		(property "Reference" "IC2"
			(at -1.035 2.69 0)
			(layer "F.SilkS")
			(effects
				(font
					(size 0.7 0.7)
					(thickness 0.15)
				)
				(justify left bottom)
			)
		)
		(property "Value" "AT24CS01_SOT23"
			(at 0.002 2.799 0)
			(layer "F.Fab")
			(hide yes)
			(effects
				(font
					(size 0.7 0.7)
					(thickness 0.15)
				)
				(justify left bottom)
			)
		)
		(property "Description" "SOT-23-5"
			(at 0 0 0)
			(layer "F.Fab")
			(hide yes)
			(effects
				(font
					(size 1.27 1.27)
					(thickness 0.15)
				)
			)
		)
		(property "Author" "Antmicro"
			(at 0 0 0)
			(layer "F.Fab")
			(hide yes)
			(effects
				(font
					(size 1 1)
					(thickness 0.15)
				)
			)
		)
		(property "License" "Apache-2.0"
			(at 0 0 0)
			(layer "F.Fab")
			(hide yes)
			(effects
				(font
					(size 1 1)
					(thickness 0.15)
				)
			)
		)
		(property "MPN" "AT24CS01-ST"
			(at 0 0 0)
			(layer "F.Fab")
			(hide yes)
			(effects
				(font
					(size 1 1)
					(thickness 0.15)
				)
			)
		)
		(property "Manufacturer" "Atmel"
			(at 0 0 0)
			(layer "F.Fab")
			(hide yes)
			(effects
				(font
					(size 1 1)
					(thickness 0.15)
				)
			)
		)
		(sheetname "EEPROM")
		(sheetfile "EEPROM.kicad_sch")
		(attr smd)
		(fp_line
			(start -0.85 1.6)
			(end -0.85 1.301)
			(stroke
				(width 0.15)
				(type solid)
			)
			(layer "F.SilkS")
		)
		(fp_line
			(start -0.8 -1.6)
			(end -0.8 -1.3)
			(stroke
				(width 0.15)
				(type solid)
			)
			(layer "F.SilkS")
		)
		(fp_line
			(start -0.8 -1.6)
			(end -0.5 -1.6)
			(stroke
				(width 0.15)
				(type solid)
			)
			(layer "F.SilkS")
		)
		(fp_line
			(start -0.55 1.6)
			(end -0.85 1.6)
			(stroke
				(width 0.15)
				(type solid)
			)
			(layer "F.SilkS")
		)
		(fp_line
			(start 0.8 -1.6)
			(end 0.5 -1.6)
			(stroke
				(width 0.15)
				(type solid)
			)
			(layer "F.SilkS")
		)
		(fp_line
			(start 0.8 -1.3)
			(end 0.8 -1.6)
			(stroke
				(width 0.15)
				(type solid)
			)
			(layer "F.SilkS")
		)
		(fp_line
			(start 0.8 0.55)
			(end 0.8 -0.55)
			(stroke
				(width 0.15)
				(type solid)
			)
			(layer "F.SilkS")
		)
		(fp_line
			(start 0.8 1.3)
			(end 0.8 1.599)
			(stroke
				(width 0.15)
				(type solid)
			)
			(layer "F.SilkS")
		)
		(fp_line
			(start 0.8 1.599)
			(end 0.549 1.599)
			(stroke
				(width 0.15)
				(type solid)
			)
			(layer "F.SilkS")
		)
		(fp_circle
			(center -1.25 -1.5)
			(end -1.2 -1.5)
			(stroke
				(width 0.15)
				(type solid)
			)
			(fill yes)
			(layer "F.SilkS")
		)
		(fp_rect
			(start 1.9 -1.76)
			(end -1.9 1.75)
			(stroke
				(width 0.05)
				(type solid)
			)
			(fill no)
			(layer "F.CrtYd")
		)
		(fp_line
			(start -0.398 -1.526)
			(end -0.874 -1.05)
			(stroke
				(width 0.15)
				(type solid)
			)
			(layer "F.Fab")
		)
		(fp_rect
			(start 0.874 1.523)
			(end -0.873 -1.525)
			(stroke
				(width 0.15)
				(type solid)
			)
			(fill no)
			(layer "F.Fab")
		)
		(pad "1" smd rect
			(at -1.351 -0.951 270)
			(size 0.55 1)
			(layers "F.Cu" "F.Mask" "F.Paste")
			(net 13 "SCL")
			(pinfunction "SCL")
			(pintype "passive")
		)
		(pad "2" smd rect
			(at -1.351 0 270)
			(size 0.55 1)
			(layers "F.Cu" "F.Mask" "F.Paste")
			(net 1 "GND")
			(pinfunction "GND")
			(pintype "passive")
		)
		(pad "3" smd rect
			(at -1.351 0.949 270)
			(size 0.55 1)
			(layers "F.Cu" "F.Mask" "F.Paste")
			(net 12 "SDA")
			(pinfunction "SDA")
			(pintype "passive")
		)
		(pad "4" smd rect
			(at 1.35 0.949 270)
			(size 0.55 1)
			(layers "F.Cu" "F.Mask" "F.Paste")
			(net 50 "1V8_SYS")
			(pinfunction "VCC")
			(pintype "passive")
		)
		(pad "5" smd rect
			(at 1.35 -0.951 270)
			(size 0.55 1)
			(layers "F.Cu" "F.Mask" "F.Paste")
			(net 1 "GND")
			(pinfunction "WP")
			(pintype "passive")
		)
	)
	(footprint "antmicro-footprints:L_0806_2016Metric"
		(layer "F.Cu")
		(at 131.725 86.45 180)
		(property "Reference" "L1"
			(at -1.695 -1.26 180)
			(layer "F.SilkS")
			(effects
				(font
					(size 0.7 0.7)
					(thickness 0.15)
				)
				(justify left bottom)
			)
		)
		(property "Value" "L_2.2u_1.5A_0806"
			(at 0 2 180)
			(layer "F.Fab")
			(hide yes)
			(effects
				(font
					(size 0.7 0.7)
					(thickness 0.15)
				)
				(justify left bottom)
			)
		)
		(property "Author" "Antmicro"
			(at 263.45 172.9 0)
			(layer "F.Fab")
			(hide yes)
			(effects
				(font
					(size 1 1)
					(thickness 0.15)
				)
			)
		)
		(property "IMax" ""
			(at 263.45 172.9 0)
			(layer "F.Fab")
			(hide yes)
			(effects
				(font
					(size 1 1)
					(thickness 0.15)
				)
			)
		)
		(property "ISat" ""
			(at 263.45 172.9 0)
			(layer "F.Fab")
			(hide yes)
			(effects
				(font
					(size 1 1)
					(thickness 0.15)
				)
			)
		)
		(property "License" "Apache-2.0"
			(at 263.45 172.9 0)
			(layer "F.Fab")
			(hide yes)
			(effects
				(font
					(size 1 1)
					(thickness 0.15)
				)
			)
		)
		(property "MPN" "1285AS-H-2R2M=P2"
			(at 263.45 172.9 0)
			(layer "F.Fab")
			(hide yes)
			(effects
				(font
					(size 1 1)
					(thickness 0.15)
				)
			)
		)
		(property "Manufacturer" "Murata"
			(at 263.45 172.9 0)
			(layer "F.Fab")
			(hide yes)
			(effects
				(font
					(size 1 1)
					(thickness 0.15)
				)
			)
		)
		(property "Size" "2.0x1.6"
			(at 263.45 172.9 0)
			(layer "F.Fab")
			(hide yes)
			(effects
				(font
					(size 1 1)
					(thickness 0.15)
				)
			)
		)
		(property "Val" "2.2uH/1.5A"
			(at 263.45 172.9 0)
			(layer "F.Fab")
			(hide yes)
			(effects
				(font
					(size 1 1)
					(thickness 0.15)
				)
			)
		)
		(sheetname "EEPROM")
		(sheetfile "EEPROM.kicad_sch")
		(attr smd)
		(fp_line
			(start -0.3 -0.9)
			(end 0.298 -0.9)
			(stroke
				(width 0.15)
				(type solid)
			)
			(layer "F.SilkS")
		)
		(fp_line
			(start -0.301 0.9)
			(end 0.299 0.9)
			(stroke
				(width 0.15)
				(type solid)
			)
			(layer "F.SilkS")
		)
		(fp_rect
			(start -1.75 -1.05)
			(end 1.75 1.05)
			(stroke
				(width 0.05)
				(type solid)
			)
			(fill no)
			(layer "F.CrtYd")
		)
		(fp_rect
			(start -0.951 -0.882)
			(end 0.949 0.875)
			(stroke
				(width 0.15)
				(type solid)
			)
			(fill no)
			(layer "F.Fab")
		)
		(pad "1" smd roundrect
			(at -1.1 -0.001 180)
			(size 1 1.8)
			(layers "F.Cu" "F.Mask" "F.Paste")
			(roundrect_rratio 0.15)
			(net 50 "1V8_SYS")
			(pintype "passive")
		)
		(pad "2" smd roundrect
			(at 1.1 -0.001 180)
			(size 1 1.8)
			(layers "F.Cu" "F.Mask" "F.Paste")
			(roundrect_rratio 0.15)
			(net 69 "Net-(U2-SW)")
			(pintype "passive")
		)
	)
	(footprint "antmicro-footprints:R_0402_1005Metric"
		(layer "F.Cu")
		(at 128.53 81.145 180)
		(descr "Resistor SMD 0402")
		(tags "resistor SMD 0402")
		(property "Reference" "R8"
			(at 0.74 0.575 180)
			(layer "F.SilkS")
			(effects
				(font
					(size 0.7 0.7)
					(thickness 0.15)
				)
				(justify left bottom)
			)
		)
		(property "Value" "R_0R_0402"
			(at 0 1.4 180)
			(layer "F.Fab")
			(hide yes)
			(effects
				(font
					(size 0.7 0.7)
					(thickness 0.15)
				)
				(justify left bottom)
			)
		)
		(property "Description" "0R resistor in 0402 package with unspecified tolerance"
			(at 0 0 180)
			(layer "F.Fab")
			(hide yes)
			(effects
				(font
					(size 1.27 1.27)
					(thickness 0.15)
				)
			)
		)
		(property "Author" "Antmicro"
			(at 257.06 162.29 0)
			(layer "F.Fab")
			(hide yes)
			(effects
				(font
					(size 1 1)
					(thickness 0.15)
				)
			)
		)
		(property "Current" "1A"
			(at 257.06 162.29 0)
			(layer "F.Fab")
			(hide yes)
			(effects
				(font
					(size 1 1)
					(thickness 0.15)
				)
			)
		)
		(property "License" "Apache-2.0"
			(at 257.06 162.29 0)
			(layer "F.Fab")
			(hide yes)
			(effects
				(font
					(size 1 1)
					(thickness 0.15)
				)
			)
		)
		(property "MPN" "ERJ2GE0R00X"
			(at 257.06 162.29 0)
			(layer "F.Fab")
			(hide yes)
			(effects
				(font
					(size 1 1)
					(thickness 0.15)
				)
			)
		)
		(property "Manufacturer" "Panasonic"
			(at 257.06 162.29 0)
			(layer "F.Fab")
			(hide yes)
			(effects
				(font
					(size 1 1)
					(thickness 0.15)
				)
			)
		)
		(property "Tolerance" ""
			(at 257.06 162.29 0)
			(layer "F.Fab")
			(hide yes)
			(effects
				(font
					(size 1 1)
					(thickness 0.15)
				)
			)
		)
		(property "Val" "0R"
			(at 257.06 162.29 0)
			(layer "F.Fab")
			(hide yes)
			(effects
				(font
					(size 1 1)
					(thickness 0.15)
				)
			)
		)
		(sheetname "EEPROM")
		(sheetfile "EEPROM.kicad_sch")
		(attr smd exclude_from_pos_files exclude_from_bom dnp)
		(fp_rect
			(start -0.925 -0.47)
			(end 0.925 0.47)
			(stroke
				(width 0.05)
				(type default)
			)
			(fill no)
			(layer "F.CrtYd")
		)
		(fp_rect
			(start -0.5 -0.25)
			(end 0.5 0.25)
			(stroke
				(width 0.15)
				(type solid)
			)
			(fill no)
			(layer "F.Fab")
		)
		(pad "1" smd roundrect
			(at -0.48 0 180)
			(size 0.59 0.64)
			(layers "F.Cu" "F.Mask" "F.Paste")
			(roundrect_rratio 0.25)
			(net 50 "1V8_SYS")
			(pintype "passive")
		)
		(pad "2" smd roundrect
			(at 0.48 0 180)
			(size 0.59 0.64)
			(layers "F.Cu" "F.Mask" "F.Paste")
			(roundrect_rratio 0.25)
			(net 52 "/EEPROM/VDD_LED")
			(pintype "passive")
		)
	)
	(footprint "antmicro-footprints:R_0402_1005Metric"
		(layer "F.Cu")
		(at 131.075 75.95 90)
		(descr "Resistor SMD 0402")
		(tags "resistor SMD 0402")
		(property "Reference" "R12"
			(at -3.05 0.345 90)
			(layer "F.SilkS")
			(effects
				(font
					(size 0.7 0.7)
					(thickness 0.15)
				)
				(justify left bottom)
			)
		)
		(property "Value" "R_220R_0402"
			(at 0 1.4 90)
			(layer "F.Fab")
			(hide yes)
			(effects
				(font
					(size 0.7 0.7)
					(thickness 0.15)
				)
				(justify left bottom)
			)
		)
		(property "Description" "220R resistor in 0402 package with 1% tolerance"
			(at 0 0 90)
			(layer "F.Fab")
			(hide yes)
			(effects
				(font
					(size 1.27 1.27)
					(thickness 0.15)
				)
			)
		)
		(property "Author" "Antmicro"
			(at 207.025 -55.125 0)
			(layer "F.Fab")
			(hide yes)
			(effects
				(font
					(size 1 1)
					(thickness 0.15)
				)
			)
		)
		(property "License" "Apache-2.0"
			(at 207.025 -55.125 0)
			(layer "F.Fab")
			(hide yes)
			(effects
				(font
					(size 1 1)
					(thickness 0.15)
				)
			)
		)
		(property "MPN" "CR0402-FX-2200GLF"
			(at 207.025 -55.125 0)
			(layer "F.Fab")
			(hide yes)
			(effects
				(font
					(size 1 1)
					(thickness 0.15)
				)
			)
		)
		(property "Manufacturer" "Bourns"
			(at 207.025 -55.125 0)
			(layer "F.Fab")
			(hide yes)
			(effects
				(font
					(size 1 1)
					(thickness 0.15)
				)
			)
		)
		(property "Tolerance" "1%"
			(at 207.025 -55.125 0)
			(layer "F.Fab")
			(hide yes)
			(effects
				(font
					(size 1 1)
					(thickness 0.15)
				)
			)
		)
		(property "Val" "220R"
			(at 207.025 -55.125 0)
			(layer "F.Fab")
			(hide yes)
			(effects
				(font
					(size 1 1)
					(thickness 0.15)
				)
			)
		)
		(sheetname "EEPROM")
		(sheetfile "EEPROM.kicad_sch")
		(attr smd)
		(fp_rect
			(start -0.925 -0.47)
			(end 0.925 0.47)
			(stroke
				(width 0.05)
				(type default)
			)
			(fill no)
			(layer "F.CrtYd")
		)
		(fp_rect
			(start -0.5 -0.25)
			(end 0.5 0.25)
			(stroke
				(width 0.15)
				(type solid)
			)
			(fill no)
			(layer "F.Fab")
		)
		(pad "1" smd roundrect
			(at -0.48 0 90)
			(size 0.59 0.64)
			(layers "F.Cu" "F.Mask" "F.Paste")
			(roundrect_rratio 0.25)
			(net 11 "Net-(IC1-P3)")
			(pintype "passive")
		)
		(pad "2" smd roundrect
			(at 0.48 0 90)
			(size 0.59 0.64)
			(layers "F.Cu" "F.Mask" "F.Paste")
			(roundrect_rratio 0.25)
			(net 7 "Net-(D4-Pad1)")
			(pintype "passive")
		)
	)
	(footprint "antmicro-footprints:TP_SMD_1mm"
		(layer "F.Cu")
		(at 129.55 88.55)
		(property "Reference" "TP2"
			(at 0.34 -0.62 90)
			(layer "F.SilkS")
			(effects
				(font
					(size 0.7 0.7)
					(thickness 0.15)
				)
				(justify left bottom)
			)
		)
		(property "Value" "TP_1mm_SMD"
			(at 0 1.4 0)
			(layer "F.Fab")
			(hide yes)
			(effects
				(font
					(size 0.7 0.7)
					(thickness 0.15)
				)
				(justify left bottom)
			)
		)
		(property "Description" "Test Point 1mm"
			(at 0 0 0)
			(layer "F.Fab")
			(hide yes)
			(effects
				(font
					(size 1.27 1.27)
					(thickness 0.15)
				)
			)
		)
		(property "Author" "Antmicro"
			(at 0 0 0)
			(layer "F.Fab")
			(hide yes)
			(effects
				(font
					(size 1 1)
					(thickness 0.15)
				)
			)
		)
		(property "License" "Apache-2.0"
			(at 0 0 0)
			(layer "F.Fab")
			(hide yes)
			(effects
				(font
					(size 1 1)
					(thickness 0.15)
				)
			)
		)
		(property "MPN" ""
			(at 0 0 0)
			(layer "F.Fab")
			(hide yes)
			(effects
				(font
					(size 1 1)
					(thickness 0.15)
				)
			)
		)
		(property "Manufacturer" ""
			(at 0 0 0)
			(layer "F.Fab")
			(hide yes)
			(effects
				(font
					(size 1 1)
					(thickness 0.15)
				)
			)
		)
		(sheetname "EEPROM")
		(sheetfile "EEPROM.kicad_sch")
		(attr exclude_from_pos_files)
		(pad "1" smd circle
			(at 0 0)
			(size 1 1)
			(layers "F.Cu" "F.Mask")
			(net 15 "Net-(IC1-P5)")
			(pinfunction "1")
			(pintype "passive")
		)
	)
	(footprint "antmicro-footprints:TP_SMD_1mm"
		(layer "F.Cu")
		(at 131.125 88.55)
		(property "Reference" "TP3"
			(at 0.525 0.29 0)
			(layer "F.SilkS")
			(effects
				(font
					(size 0.7 0.7)
					(thickness 0.15)
				)
				(justify left bottom)
			)
		)
		(property "Value" "TP_1mm_SMD"
			(at 0 1.4 0)
			(layer "F.Fab")
			(hide yes)
			(effects
				(font
					(size 0.7 0.7)
					(thickness 0.15)
				)
				(justify left bottom)
			)
		)
		(property "Description" "Test Point 1mm"
			(at 0 0 0)
			(layer "F.Fab")
			(hide yes)
			(effects
				(font
					(size 1.27 1.27)
					(thickness 0.15)
				)
			)
		)
		(property "Author" "Antmicro"
			(at 0 0 0)
			(layer "F.Fab")
			(hide yes)
			(effects
				(font
					(size 1 1)
					(thickness 0.15)
				)
			)
		)
		(property "License" "Apache-2.0"
			(at 0 0 0)
			(layer "F.Fab")
			(hide yes)
			(effects
				(font
					(size 1 1)
					(thickness 0.15)
				)
			)
		)
		(property "MPN" ""
			(at 0 0 0)
			(layer "F.Fab")
			(hide yes)
			(effects
				(font
					(size 1 1)
					(thickness 0.15)
				)
			)
		)
		(property "Manufacturer" ""
			(at 0 0 0)
			(layer "F.Fab")
			(hide yes)
			(effects
				(font
					(size 1 1)
					(thickness 0.15)
				)
			)
		)
		(sheetname "EEPROM")
		(sheetfile "EEPROM.kicad_sch")
		(attr exclude_from_pos_files)
		(pad "1" smd circle
			(at 0 0)
			(size 1 1)
			(layers "F.Cu" "F.Mask")
			(net 1 "GND")
			(pinfunction "1")
			(pintype "passive")
		)
	)
)
